(kicad_pcb
	(version 20260206)
	(generator "pcbnew")
	(generator_version "10.0")
	(general
		(thickness 1.6)
		(legacy_teardrops no)
	)
	(paper "A4")
	(title_block
		(title "Bryce Canyon_R.DPB_16317-1_OCP.brd")
		(comment 1 "Bryce Canyon / footprints 432-439 of 2099")
	)
	(layers
		(0 "F.Cu" signal "TOP")
		(4 "In1.Cu" signal "L2GND")
		(6 "In2.Cu" signal "L3")
		(8 "In3.Cu" signal "L4VCC")
		(10 "In4.Cu" signal "L5VCC")
		(12 "In5.Cu" signal "L6")
		(14 "In6.Cu" signal "L7GND")
		(2 "B.Cu" signal "BOTTOM")
		(9 "F.Adhes" user "F.Adhesive")
		(11 "B.Adhes" user "B.Adhesive")
		(13 "F.Paste" user "Package Geometry/Pastemask Top")
		(15 "B.Paste" user "Package Geometry/Pastemask Bottom")
		(5 "F.SilkS" user "Ref Des/Silkscreen Top")
		(7 "B.SilkS" user "Ref Des/Silkscreen Bottom")
		(1 "F.Mask" user "Board Geometry/Soldermask Top")
		(3 "B.Mask" user "Board Geometry/Soldermask Bottom")
		(17 "Dwgs.User" user "User.Drawings")
		(19 "Cmts.User" user "User.Comments")
		(21 "Eco1.User" user "User.Eco1")
		(23 "Eco2.User" user "User.Eco2")
		(25 "Edge.Cuts" user "Board Geometry/Outline")
		(27 "Margin" user)
		(31 "F.CrtYd" user "Package Geometry/Place Bound Top")
		(29 "B.CrtYd" user "Package Geometry/Place Bound Bottom")
		(35 "F.Fab" user "Ref Des/Assembly Top")
		(33 "B.Fab" user "Ref Des/Assembly Bottom")
	)
	(footprint ""
		(layer "F.Cu")
		(at 81.534 -131.572)
		(property "Reference" "R409"
			(at 0 0 0)
			(layer "F.SilkS")
			(hide yes)
			(effects
				(font
					(size 1.27 1.27)
				)
			)
		)
		(property "Value" "0R2J-2-GP"
			(at 0.064008 -3.993896 0)
			(unlocked yes)
			(layer "F.Fab")
			(hide yes)
			(effects
				(font
					(size 1.016 1.016)
					(thickness 0.1524)
				)
			)
		)
		(property "Device Type" "R402H16"
			(at 0.064008 -5.517896 0)
			(unlocked yes)
			(layer "F.Fab")
			(hide yes)
			(effects
				(font
					(size 1.016 1.016)
					(thickness 0.1524)
				)
			)
		)
		(duplicate_pad_numbers_are_jumpers no)
		(fp_line
			(start -0.508 -0.9398)
			(end -0.508 0.9398)
			(stroke
				(width 0.1524)
				(type default)
			)
			(layer "F.SilkS")
		)
		(fp_line
			(start 0.508 -0.9398)
			(end -0.508 -0.9398)
			(stroke
				(width 0.1524)
				(type default)
			)
			(layer "F.SilkS")
		)
		(fp_rect
			(start -0.508 0.9398)
			(end 0.508 -0.9398)
			(stroke
				(width 0)
				(type default)
			)
			(fill no)
			(layer "F.CrtYd")
		)
		(fp_rect
			(start -0.508 0.9398)
			(end 0.508 -0.9398)
			(stroke
				(width 0)
				(type default)
			)
			(fill no)
			(layer "F.Fab")
		)
		(pad "1" smd custom
			(at 0 -0.4445)
			(size 0.1397 0.1397)
			(layers "F.Cu" "F.Mask" "F.Paste")
			(net "SW_HDD_G14")
			(options
				(clearance outline)
				(anchor circle)
			)
			(primitives
				(gr_poly
					(pts
						(arc
							(start -0.1778 -0.2794)
							(mid -0.249642 -0.249642)
							(end -0.2794 -0.1778)
						)
						(arc
							(start -0.2794 0.1778)
							(mid -0.249642 0.249642)
							(end -0.1778 0.2794)
						)
						(arc
							(start 0.1778 0.2794)
							(mid 0.249642 0.249642)
							(end 0.2794 0.1778)
						)
						(arc
							(start 0.2794 -0.1778)
							(mid 0.249642 -0.249642)
							(end 0.1778 -0.2794)
						)
					)
					(width 0)
					(fill yes)
				)
			)
		)
		(pad "2" smd custom
			(at 0 0.4445)
			(size 0.1397 0.1397)
			(layers "F.Cu" "F.Mask" "F.Paste")
			(net "SW_HDD_R14")
			(options
				(clearance outline)
				(anchor circle)
			)
			(primitives
				(gr_poly
					(pts
						(arc
							(start -0.1778 -0.2794)
							(mid -0.249642 -0.249642)
							(end -0.2794 -0.1778)
						)
						(arc
							(start -0.2794 0.1778)
							(mid -0.249642 0.249642)
							(end -0.1778 0.2794)
						)
						(arc
							(start 0.1778 0.2794)
							(mid 0.249642 0.249642)
							(end 0.2794 0.1778)
						)
						(arc
							(start 0.2794 -0.1778)
							(mid 0.249642 -0.249642)
							(end 0.1778 -0.2794)
						)
					)
					(width 0)
					(fill yes)
				)
			)
		)
	)
	(footprint ""
		(layer "F.Cu")
		(at 382.88595 -128.627124 180)
		(property "Reference" "VIA41"
			(at 0 0 180)
			(layer "F.SilkS")
			(hide yes)
			(effects
				(font
					(size 1.27 1.27)
				)
			)
		)
		(property "Value" "100OHM-8L-2D36MM-L18-GP"
			(at 3.8989 0.5715 180)
			(unlocked yes)
			(layer "F.Fab")
			(hide yes)
			(effects
				(font
					(size 1.016 1.016)
					(thickness 0.1524)
				)
			)
		)
		(property "Device Type" "VIA-PCIE-4P-414097"
			(at 3.8989 -0.9525 180)
			(unlocked yes)
			(layer "F.Fab")
			(hide yes)
			(effects
				(font
					(size 1.016 1.016)
					(thickness 0.1524)
				)
			)
		)
		(duplicate_pad_numbers_are_jumpers no)
		(fp_rect
			(start -2.0701 0.4826)
			(end 2.0701 -0.4826)
			(stroke
				(width 0)
				(type default)
			)
			(fill no)
			(layer "F.CrtYd")
		)
		(fp_rect
			(start -2.0701 0.4826)
			(end 2.0701 -0.4826)
			(stroke
				(width 0)
				(type default)
			)
			(fill no)
			(layer "F.Fab")
		)
		(pad "1" thru_hole circle
			(at -1.5875 0 180)
			(size 0.508 0.508)
			(drill 0.254)
			(layers "*.Cu" "*.Mask")
			(remove_unused_layers no)
			(net "GND")
			(clearance 0.2286)
			(thermal_gap 0.2286)
		)
		(pad "2" thru_hole circle
			(at -0.5715 0 180)
			(size 0.508 0.508)
			(drill 0.254)
			(layers "*.Cu" "*.Mask")
			(remove_unused_layers no)
			(net "PHY_SCC_B_TO_DRV_B_20_DP")
			(clearance 0.2286)
			(thermal_gap 0.2286)
		)
		(pad "3" thru_hole circle
			(at 0.5715 0 180)
			(size 0.508 0.508)
			(drill 0.254)
			(layers "*.Cu" "*.Mask")
			(remove_unused_layers no)
			(net "PHY_SCC_B_TO_DRV_B_20_DN")
			(clearance 0.2286)
			(thermal_gap 0.2286)
		)
		(pad "4" thru_hole circle
			(at 1.5875 0 180)
			(size 0.508 0.508)
			(drill 0.254)
			(layers "*.Cu" "*.Mask")
			(remove_unused_layers no)
			(net "GND")
			(clearance 0.2286)
			(thermal_gap 0.2286)
		)
	)
	(footprint ""
		(layer "F.Cu")
		(at 395.478 -151.892 180)
		(property "Reference" "C291"
			(at 0 0 180)
			(layer "F.SilkS")
			(hide yes)
			(effects
				(font
					(size 1.27 1.27)
				)
			)
		)
		(property "Value" "SC10U16V6KX-2GP"
			(at -0.0762 -5.1308 180)
			(unlocked yes)
			(layer "F.Fab")
			(hide yes)
			(effects
				(font
					(size 1.016 1.016)
					(thickness 0.1524)
				)
			)
		)
		(property "Device Type" "C1206H71"
			(at -0.127 -6.6548 180)
			(unlocked yes)
			(layer "F.Fab")
			(hide yes)
			(effects
				(font
					(size 1.016 1.016)
					(thickness 0.1524)
				)
			)
		)
		(duplicate_pad_numbers_are_jumpers no)
		(fp_line
			(start 1.016 2.2352)
			(end -1.016 2.2352)
			(stroke
				(width 0.1524)
				(type default)
			)
			(layer "F.SilkS")
		)
		(fp_line
			(start 1.016 0.8382)
			(end 1.016 2.2352)
			(stroke
				(width 0.1524)
				(type default)
			)
			(layer "F.SilkS")
		)
		(fp_line
			(start 1.016 -2.2352)
			(end 1.016 -0.8382)
			(stroke
				(width 0.1524)
				(type default)
			)
			(layer "F.SilkS")
		)
		(fp_line
			(start -1.016 2.2352)
			(end -1.016 0.8382)
			(stroke
				(width 0.1524)
				(type default)
			)
			(layer "F.SilkS")
		)
		(fp_line
			(start -1.016 -0.8382)
			(end -1.016 -2.2352)
			(stroke
				(width 0.1524)
				(type default)
			)
			(layer "F.SilkS")
		)
		(fp_line
			(start -1.016 -2.2352)
			(end 1.016 -2.2352)
			(stroke
				(width 0.1524)
				(type default)
			)
			(layer "F.SilkS")
		)
		(fp_rect
			(start -1.0922 2.3114)
			(end 1.0922 -2.3114)
			(stroke
				(width 0)
				(type default)
			)
			(fill no)
			(layer "F.CrtYd")
		)
		(fp_poly
			(pts
				(xy 1.0922 -2.3114) (xy 1.0922 2.3114) (xy -1.0922 2.3114) (xy -1.0922 -2.3114)
			)
			(stroke
				(width 0)
				(type default)
			)
			(fill no)
			(layer "F.Fab")
		)
		(pad "1" smd rect
			(at 0 -1.397 180)
			(size 1.651 1.27)
			(layers "F.Cu" "F.Mask" "F.Paste")
			(net "P5V_HDD20")
		)
		(pad "2" smd rect
			(at 0 1.397 180)
			(size 1.651 1.27)
			(layers "F.Cu" "F.Mask" "F.Paste")
			(net "GND")
		)
	)
	(footprint ""
		(layer "F.Cu")
		(at 321.634612 -245.219474 -90)
		(property "Reference" "C106"
			(at 0 0 270)
			(layer "F.SilkS")
			(hide yes)
			(effects
				(font
					(size 1.27 1.27)
				)
			)
		)
		(property "Value" "SCD01U16V1KX-GP"
			(at -2.8321 -1.7399 270)
			(unlocked yes)
			(layer "F.Fab")
			(hide yes)
			(effects
				(font
					(size 1.016 1.016)
					(thickness 0.1524)
				)
			)
		)
		(property "Device Type" "C0201H13"
			(at -2.8321 -3.2639 270)
			(unlocked yes)
			(layer "F.Fab")
			(hide yes)
			(effects
				(font
					(size 1.016 1.016)
					(thickness 0.1524)
				)
			)
		)
		(duplicate_pad_numbers_are_jumpers no)
		(fp_rect
			(start -0.2794 0.6477)
			(end 0.2794 -0.6477)
			(stroke
				(width 0)
				(type default)
			)
			(fill no)
			(layer "F.CrtYd")
		)
		(fp_rect
			(start -0.2794 0.6477)
			(end 0.2794 -0.6477)
			(stroke
				(width 0)
				(type default)
			)
			(fill no)
			(layer "F.Fab")
		)
		(pad "1" smd custom
			(at 0 -0.2794 270)
			(size 0.0762 0.0762)
			(layers "F.Cu" "F.Mask" "F.Paste")
			(net "SAS_HDD_RX_N6")
			(options
				(clearance outline)
				(anchor circle)
			)
			(primitives
				(gr_poly
					(pts
						(arc
							(start 0.1524 -0.127)
							(mid 0.137521 -0.162921)
							(end 0.1016 -0.1778)
						)
						(arc
							(start -0.1016 -0.1778)
							(mid -0.137521 -0.162921)
							(end -0.1524 -0.127)
						)
						(arc
							(start -0.1524 0.127)
							(mid -0.137521 0.162921)
							(end -0.1016 0.1778)
						)
						(arc
							(start 0.1016 0.1778)
							(mid 0.137521 0.162921)
							(end 0.1524 0.127)
						)
					)
					(width 0)
					(fill yes)
				)
			)
		)
		(pad "2" smd custom
			(at 0 0.2794 270)
			(size 0.0762 0.0762)
			(layers "F.Cu" "F.Mask" "F.Paste")
			(net "PHY_SCC_B_TO_DRV_B_6_DN")
			(options
				(clearance outline)
				(anchor circle)
			)
			(primitives
				(gr_poly
					(pts
						(arc
							(start 0.1524 -0.127)
							(mid 0.137521 -0.162921)
							(end 0.1016 -0.1778)
						)
						(arc
							(start -0.1016 -0.1778)
							(mid -0.137521 -0.162921)
							(end -0.1524 -0.127)
						)
						(arc
							(start -0.1524 0.127)
							(mid -0.137521 0.162921)
							(end -0.1016 0.1778)
						)
						(arc
							(start 0.1016 0.1778)
							(mid 0.137521 0.162921)
							(end 0.1524 0.127)
						)
					)
					(width 0)
					(fill yes)
				)
			)
		)
	)
	(footprint ""
		(layer "F.Cu")
		(at 363.1184 -250.5456 -90)
		(property "Reference" "C129"
			(at 0 0 270)
			(layer "F.SilkS")
			(hide yes)
			(effects
				(font
					(size 1.27 1.27)
				)
			)
		)
		(property "Value" "SCD033U25V2KX-GP"
			(at 1.1811 -2.7051 270)
			(unlocked yes)
			(layer "F.Fab")
			(hide yes)
			(effects
				(font
					(size 1.016 1.016)
					(thickness 0.1524)
				)
			)
		)
		(property "Device Type" "C402H22"
			(at 1.1811 -4.2291 270)
			(unlocked yes)
			(layer "F.Fab")
			(hide yes)
			(effects
				(font
					(size 1.016 1.016)
					(thickness 0.1524)
				)
			)
		)
		(duplicate_pad_numbers_are_jumpers no)
		(fp_rect
			(start -0.4318 0.9525)
			(end 0.4318 -0.9525)
			(stroke
				(width 0)
				(type default)
			)
			(fill no)
			(layer "F.CrtYd")
		)
		(fp_rect
			(start -0.4318 0.9525)
			(end 0.4318 -0.9525)
			(stroke
				(width 0)
				(type default)
			)
			(fill no)
			(layer "F.Fab")
		)
		(pad "1" smd custom
			(at 0 -0.4445 270)
			(size 0.1524 0.1524)
			(layers "F.Cu" "F.Mask" "F.Paste")
			(net "SW_HDD_P7")
			(options
				(clearance outline)
				(anchor circle)
			)
			(primitives
				(gr_poly
					(pts
						(arc
							(start 0.3048 -0.2032)
							(mid 0.275042 -0.275042)
							(end 0.2032 -0.3048)
						)
						(arc
							(start -0.2032 -0.3048)
							(mid -0.275042 -0.275042)
							(end -0.3048 -0.2032)
						)
						(arc
							(start -0.3048 0.2032)
							(mid -0.275042 0.275042)
							(end -0.2032 0.3048)
						)
						(arc
							(start 0.2032 0.3048)
							(mid 0.275042 0.275042)
							(end 0.3048 0.2032)
						)
					)
					(width 0)
					(fill yes)
				)
			)
		)
		(pad "2" smd custom
			(at 0 0.4445 270)
			(size 0.1524 0.1524)
			(layers "F.Cu" "F.Mask" "F.Paste")
			(net "GND")
			(options
				(clearance outline)
				(anchor circle)
			)
			(primitives
				(gr_poly
					(pts
						(arc
							(start 0.3048 -0.2032)
							(mid 0.275042 -0.275042)
							(end 0.2032 -0.3048)
						)
						(arc
							(start -0.2032 -0.3048)
							(mid -0.275042 -0.275042)
							(end -0.3048 -0.2032)
						)
						(arc
							(start -0.3048 0.2032)
							(mid -0.275042 0.275042)
							(end -0.2032 0.3048)
						)
						(arc
							(start 0.2032 0.3048)
							(mid 0.275042 0.275042)
							(end 0.3048 0.2032)
						)
					)
					(width 0)
					(fill yes)
				)
			)
		)
	)
	(footprint ""
		(layer "F.Cu")
		(at 427.0756 -20.574 90)
		(property "Reference" "C467"
			(at 0 0 90)
			(layer "F.SilkS")
			(hide yes)
			(effects
				(font
					(size 1.27 1.27)
				)
			)
		)
		(property "Value" "SCD033U25V2KX-GP"
			(at 1.1811 -2.7051 90)
			(unlocked yes)
			(layer "F.Fab")
			(hide yes)
			(effects
				(font
					(size 1.016 1.016)
					(thickness 0.1524)
				)
			)
		)
		(property "Device Type" "C402H22"
			(at 1.1811 -4.2291 90)
			(unlocked yes)
			(layer "F.Fab")
			(hide yes)
			(effects
				(font
					(size 1.016 1.016)
					(thickness 0.1524)
				)
			)
		)
		(duplicate_pad_numbers_are_jumpers no)
		(fp_rect
			(start -0.4318 0.9525)
			(end 0.4318 -0.9525)
			(stroke
				(width 0)
				(type default)
			)
			(fill no)
			(layer "F.CrtYd")
		)
		(fp_rect
			(start -0.4318 0.9525)
			(end 0.4318 -0.9525)
			(stroke
				(width 0)
				(type default)
			)
			(fill no)
			(layer "F.Fab")
		)
		(pad "1" smd custom
			(at 0 -0.4445 90)
			(size 0.1524 0.1524)
			(layers "F.Cu" "F.Mask" "F.Paste")
			(net "SW_HDD_P33")
			(options
				(clearance outline)
				(anchor circle)
			)
			(primitives
				(gr_poly
					(pts
						(arc
							(start 0.3048 -0.2032)
							(mid 0.275042 -0.275042)
							(end 0.2032 -0.3048)
						)
						(arc
							(start -0.2032 -0.3048)
							(mid -0.275042 -0.275042)
							(end -0.3048 -0.2032)
						)
						(arc
							(start -0.3048 0.2032)
							(mid -0.275042 0.275042)
							(end -0.2032 0.3048)
						)
						(arc
							(start 0.2032 0.3048)
							(mid 0.275042 0.275042)
							(end 0.3048 0.2032)
						)
					)
					(width 0)
					(fill yes)
				)
			)
		)
		(pad "2" smd custom
			(at 0 0.4445 90)
			(size 0.1524 0.1524)
			(layers "F.Cu" "F.Mask" "F.Paste")
			(net "GND")
			(options
				(clearance outline)
				(anchor circle)
			)
			(primitives
				(gr_poly
					(pts
						(arc
							(start 0.3048 -0.2032)
							(mid 0.275042 -0.275042)
							(end 0.2032 -0.3048)
						)
						(arc
							(start -0.2032 -0.3048)
							(mid -0.275042 -0.275042)
							(end -0.3048 -0.2032)
						)
						(arc
							(start -0.3048 0.2032)
							(mid -0.275042 0.275042)
							(end -0.2032 0.3048)
						)
						(arc
							(start 0.2032 0.3048)
							(mid 0.275042 0.275042)
							(end 0.3048 0.2032)
						)
					)
					(width 0)
					(fill yes)
				)
			)
		)
	)
	(footprint ""
		(layer "F.Cu")
		(at 312.9534 -340.812882 180)
		(property "Reference" "R159"
			(at 0 0 180)
			(layer "F.SilkS")
			(hide yes)
			(effects
				(font
					(size 1.27 1.27)
				)
			)
		)
		(property "Value" "4K7R2F-GP"
			(at 0.064008 -3.993896 180)
			(unlocked yes)
			(layer "F.Fab")
			(hide yes)
			(effects
				(font
					(size 1.016 1.016)
					(thickness 0.1524)
				)
			)
		)
		(property "Device Type" "R402H16"
			(at 0.064008 -5.517896 180)
			(unlocked yes)
			(layer "F.Fab")
			(hide yes)
			(effects
				(font
					(size 1.016 1.016)
					(thickness 0.1524)
				)
			)
		)
		(duplicate_pad_numbers_are_jumpers no)
		(fp_line
			(start 0.508 -0.9398)
			(end -0.508 -0.9398)
			(stroke
				(width 0.1524)
				(type default)
			)
			(layer "F.SilkS")
		)
		(fp_line
			(start -0.508 -0.9398)
			(end -0.508 0.9398)
			(stroke
				(width 0.1524)
				(type default)
			)
			(layer "F.SilkS")
		)
		(fp_rect
			(start -0.508 0.9398)
			(end 0.508 -0.9398)
			(stroke
				(width 0)
				(type default)
			)
			(fill no)
			(layer "F.CrtYd")
		)
		(fp_rect
			(start -0.508 0.9398)
			(end 0.508 -0.9398)
			(stroke
				(width 0)
				(type default)
			)
			(fill no)
			(layer "F.Fab")
		)
		(pad "1" smd custom
			(at 0 -0.4445 180)
			(size 0.1397 0.1397)
			(layers "F.Cu" "F.Mask" "F.Paste")
			(net "THERMHOT#_D")
			(options
				(clearance outline)
				(anchor circle)
			)
			(primitives
				(gr_poly
					(pts
						(arc
							(start -0.1778 -0.2794)
							(mid -0.249642 -0.249642)
							(end -0.2794 -0.1778)
						)
						(arc
							(start -0.2794 0.1778)
							(mid -0.249642 0.249642)
							(end -0.1778 0.2794)
						)
						(arc
							(start 0.1778 0.2794)
							(mid 0.249642 0.249642)
							(end 0.2794 0.1778)
						)
						(arc
							(start 0.2794 -0.1778)
							(mid 0.249642 -0.249642)
							(end 0.1778 -0.2794)
						)
					)
					(width 0)
					(fill yes)
				)
			)
		)
		(pad "2" smd custom
			(at 0 0.4445 180)
			(size 0.1397 0.1397)
			(layers "F.Cu" "F.Mask" "F.Paste")
			(net "GND")
			(options
				(clearance outline)
				(anchor circle)
			)
			(primitives
				(gr_poly
					(pts
						(arc
							(start -0.1778 -0.2794)
							(mid -0.249642 -0.249642)
							(end -0.2794 -0.1778)
						)
						(arc
							(start -0.2794 0.1778)
							(mid -0.249642 0.249642)
							(end -0.1778 0.2794)
						)
						(arc
							(start 0.1778 0.2794)
							(mid 0.249642 0.249642)
							(end 0.2794 0.1778)
						)
						(arc
							(start 0.2794 -0.1778)
							(mid 0.249642 -0.249642)
							(end 0.1778 -0.2794)
						)
					)
					(width 0)
					(fill yes)
				)
			)
		)
	)
	(footprint ""
		(layer "F.Cu")
		(at 353.3648 -31.6484)
		(property "Reference" "C440"
			(at 0 0 0)
			(layer "F.SilkS")
			(hide yes)
			(effects
				(font
					(size 1.27 1.27)
				)
			)
		)
		(property "Value" "SCD01U50V2KX-1GP"
			(at 1.1811 -2.7051 0)
			(unlocked yes)
			(layer "F.Fab")
			(hide yes)
			(effects
				(font
					(size 1.016 1.016)
					(thickness 0.1524)
				)
			)
		)
		(property "Device Type" "C402H22"
			(at 1.1811 -4.2291 0)
			(unlocked yes)
			(layer "F.Fab")
			(hide yes)
			(effects
				(font
					(size 1.016 1.016)
					(thickness 0.1524)
				)
			)
		)
		(duplicate_pad_numbers_are_jumpers no)
		(fp_rect
			(start -0.4318 0.9525)
			(end 0.4318 -0.9525)
			(stroke
				(width 0)
				(type default)
			)
			(fill no)
			(layer "F.CrtYd")
		)
		(fp_rect
			(start -0.4318 0.9525)
			(end 0.4318 -0.9525)
			(stroke
				(width 0)
				(type default)
			)
			(fill no)
			(layer "F.Fab")
		)
		(pad "1" smd custom
			(at 0 -0.4445)
			(size 0.1524 0.1524)
			(layers "F.Cu" "F.Mask" "F.Paste")
			(net "HDD_PRSNT_31")
			(options
				(clearance outline)
				(anchor circle)
			)
			(primitives
				(gr_poly
					(pts
						(arc
							(start 0.3048 -0.2032)
							(mid 0.275042 -0.275042)
							(end 0.2032 -0.3048)
						)
						(arc
							(start -0.2032 -0.3048)
							(mid -0.275042 -0.275042)
							(end -0.3048 -0.2032)
						)
						(arc
							(start -0.3048 0.2032)
							(mid -0.275042 0.275042)
							(end -0.2032 0.3048)
						)
						(arc
							(start 0.2032 0.3048)
							(mid 0.275042 0.275042)
							(end 0.3048 0.2032)
						)
					)
					(width 0)
					(fill yes)
				)
			)
		)
		(pad "2" smd custom
			(at 0 0.4445)
			(size 0.1524 0.1524)
			(layers "F.Cu" "F.Mask" "F.Paste")
			(net "GND")
			(options
				(clearance outline)
				(anchor circle)
			)
			(primitives
				(gr_poly
					(pts
						(arc
							(start 0.3048 -0.2032)
							(mid 0.275042 -0.275042)
							(end 0.2032 -0.3048)
						)
						(arc
							(start -0.2032 -0.3048)
							(mid -0.275042 -0.275042)
							(end -0.3048 -0.2032)
						)
						(arc
							(start -0.3048 0.2032)
							(mid -0.275042 0.275042)
							(end -0.2032 0.3048)
						)
						(arc
							(start 0.2032 0.3048)
							(mid 0.275042 0.275042)
							(end 0.3048 0.2032)
						)
					)
					(width 0)
					(fill yes)
				)
			)
		)
	)
)
